# S9S_MB_2U (Grand Teton) — schematic netlist excerpt (pin names and nets, part order shuffled) for the footprints in the layout excerpt that follows; sources: Cadence DE-HDL packaged netlist, KiCad conversion of 03242023_DA0F0TMBIJ0_F0T_Motherboard_J_brd_V01_OCP.brd

R3553  Q_RES  33.2 1% CHIP  pkg 0402LF  page 170 : A = SMB_LM75_3_3V3AUX_SCL ; B = SMB_LM75_3_3V3AUX_SCL_R1
R2375  Q_RES  1K 1% CHIP  pkg 0402LF  page 266 : A = P3V3_AUX ; B = PVCCIN_CPU0_PIN_ALERT

(kicad_pcb
	(version 20260206)
	(generator "pcbnew")
	(generator_version "10.0")
	(general
		(thickness 1.6)
		(legacy_teardrops no)
	)
	(paper "A4")
	(title_block
		(title "03242023_DA0F0TMBIJ0_F0T_Motherboard_J_brd_V01_OCP.brd")
		(comment 1 "Grand Teton / footprints 1336-1337 of 6105")
	)
	(layers
		(0 "F.Cu" signal "TOP")
		(4 "In1.Cu" signal "GND")
		(6 "In2.Cu" signal "IN1")
		(8 "In3.Cu" signal "GND1")
		(10 "In4.Cu" signal "IN2")
		(12 "In5.Cu" signal "GND2")
		(14 "In6.Cu" signal "IN3")
		(16 "In7.Cu" signal "GND3")
		(18 "In8.Cu" signal "VCC")
		(20 "In9.Cu" signal "VCC1")
		(22 "In10.Cu" signal "GND4")
		(24 "In11.Cu" signal "IN4")
		(26 "In12.Cu" signal "GND5")
		(28 "In13.Cu" signal "IN5")
		(30 "In14.Cu" signal "GND6")
		(32 "In15.Cu" signal "IN6")
		(34 "In16.Cu" signal "GND7")
		(2 "B.Cu" signal "BOTTOM")
		(9 "F.Adhes" user "F.Adhesive")
		(11 "B.Adhes" user "B.Adhesive")
		(13 "F.Paste" user "Package Geometry/Pastemask Top")
		(15 "B.Paste" user "Package Geometry/Pastemask Bottom")
		(5 "F.SilkS" user "Ref Des/Silkscreen Top")
		(7 "B.SilkS" user "Ref Des/Silkscreen Bottom")
		(1 "F.Mask" user "Board Geometry/Soldermask Top")
		(3 "B.Mask" user "Board Geometry/Soldermask Bottom")
		(17 "Dwgs.User" user "User.Drawings")
		(19 "Cmts.User" user "User.Comments")
		(21 "Eco1.User" user "User.Eco1")
		(23 "Eco2.User" user "User.Eco2")
		(25 "Edge.Cuts" user "Board Geometry/Outline")
		(27 "Margin" user)
		(31 "F.CrtYd" user "Package Geometry/Place Bound Top")
		(29 "B.CrtYd" user "Package Geometry/Place Bound Bottom")
		(35 "F.Fab" user "Ref Des/Assembly Top")
		(33 "B.Fab" user "Ref Des/Assembly Bottom")
	)
	(footprint ""
		(layer "F.Cu")
		(at 348.606364 -358.906826)
		(property "Reference" "R2375"
			(at 0 0 0)
			(layer "F.SilkS")
			(hide yes)
			(effects
				(font
					(size 1.27 1.27)
				)
			)
		)
		(property "Value" ""
			(at 0 0 0)
			(layer "F.Fab")
			(effects
				(font
					(size 1.27 1.27)
				)
			)
		)
		(duplicate_pad_numbers_are_jumpers no)
		(fp_line
			(start -0.7874 -0.4064)
			(end 0.7874 -0.4064)
			(stroke
				(width 0.1524)
				(type default)
			)
			(layer "F.SilkS")
		)
		(fp_line
			(start -0.7874 0.4064)
			(end -0.7874 -0.4064)
			(stroke
				(width 0.1524)
				(type default)
			)
			(layer "F.SilkS")
		)
		(fp_line
			(start 0.7874 -0.4064)
			(end 0.7874 0.4064)
			(stroke
				(width 0.1524)
				(type default)
			)
			(layer "F.SilkS")
		)
		(fp_line
			(start 0.7874 0.4064)
			(end -0.7874 0.4064)
			(stroke
				(width 0.1524)
				(type default)
			)
			(layer "F.SilkS")
		)
		(fp_line
			(start -0.67945 -0.305054)
			(end -0.12065 -0.305054)
			(stroke
				(width 0.1)
				(type default)
			)
			(layer "F.Fab")
		)
		(fp_line
			(start -0.67945 0.3048)
			(end -0.67945 -0.305054)
			(stroke
				(width 0.1)
				(type default)
			)
			(layer "F.Fab")
		)
		(fp_line
			(start -0.12065 -0.305054)
			(end -0.12065 -0.2794)
			(stroke
				(width 0.1)
				(type default)
			)
			(layer "F.Fab")
		)
		(fp_line
			(start -0.12065 -0.2794)
			(end 0.12065 -0.2794)
			(stroke
				(width 0.1)
				(type default)
			)
			(layer "F.Fab")
		)
		(fp_line
			(start -0.12065 0.2794)
			(end -0.12065 0.3048)
			(stroke
				(width 0.1)
				(type default)
			)
			(layer "F.Fab")
		)
		(fp_line
			(start -0.12065 0.3048)
			(end -0.67945 0.3048)
			(stroke
				(width 0.1)
				(type default)
			)
			(layer "F.Fab")
		)
		(fp_line
			(start 0.120396 0.2794)
			(end -0.12065 0.2794)
			(stroke
				(width 0.1)
				(type default)
			)
			(layer "F.Fab")
		)
		(fp_line
			(start 0.120396 0.3048)
			(end 0.120396 0.2794)
			(stroke
				(width 0.1)
				(type default)
			)
			(layer "F.Fab")
		)
		(fp_line
			(start 0.12065 -0.3048)
			(end 0.67945 -0.3048)
			(stroke
				(width 0.1)
				(type default)
			)
			(layer "F.Fab")
		)
		(fp_line
			(start 0.12065 -0.2794)
			(end 0.12065 -0.3048)
			(stroke
				(width 0.1)
				(type default)
			)
			(layer "F.Fab")
		)
		(fp_line
			(start 0.67945 -0.3048)
			(end 0.67945 0.3048)
			(stroke
				(width 0.1)
				(type default)
			)
			(layer "F.Fab")
		)
		(fp_line
			(start 0.67945 0.3048)
			(end 0.120396 0.3048)
			(stroke
				(width 0.1)
				(type default)
			)
			(layer "F.Fab")
		)
		(pad "1" smd circle
			(at -0.40005 0)
			(size 0 0)
			(layers "F.Cu" "F.Mask" "F.Paste")
			(net "P3V3_AUX")
		)
		(pad "2" smd circle
			(at 0.40005 0)
			(size 0 0)
			(layers "F.Cu" "F.Mask" "F.Paste")
			(net "PVCCIN_CPU0_PIN_ALERT")
		)
	)
	(footprint ""
		(layer "F.Cu")
		(at 107.019598 -15.91691)
		(property "Reference" "R3553"
			(at 0 0 0)
			(layer "F.SilkS")
			(hide yes)
			(effects
				(font
					(size 1.27 1.27)
				)
			)
		)
		(property "Value" ""
			(at 0 0 0)
			(layer "F.Fab")
			(effects
				(font
					(size 1.27 1.27)
				)
			)
		)
		(duplicate_pad_numbers_are_jumpers no)
		(fp_line
			(start -0.7874 -0.4064)
			(end 0.7874 -0.4064)
			(stroke
				(width 0.1524)
				(type default)
			)
			(layer "F.SilkS")
		)
		(fp_line
			(start -0.7874 0.4064)
			(end -0.7874 -0.4064)
			(stroke
				(width 0.1524)
				(type default)
			)
			(layer "F.SilkS")
		)
		(fp_line
			(start 0.7874 -0.4064)
			(end 0.7874 0.4064)
			(stroke
				(width 0.1524)
				(type default)
			)
			(layer "F.SilkS")
		)
		(fp_line
			(start 0.7874 0.4064)
			(end -0.7874 0.4064)
			(stroke
				(width 0.1524)
				(type default)
			)
			(layer "F.SilkS")
		)
		(fp_line
			(start -0.67945 -0.305054)
			(end -0.12065 -0.305054)
			(stroke
				(width 0.1)
				(type default)
			)
			(layer "F.Fab")
		)
		(fp_line
			(start -0.67945 0.3048)
			(end -0.67945 -0.305054)
			(stroke
				(width 0.1)
				(type default)
			)
			(layer "F.Fab")
		)
		(fp_line
			(start -0.12065 -0.305054)
			(end -0.12065 -0.2794)
			(stroke
				(width 0.1)
				(type default)
			)
			(layer "F.Fab")
		)
		(fp_line
			(start -0.12065 -0.2794)
			(end 0.12065 -0.2794)
			(stroke
				(width 0.1)
				(type default)
			)
			(layer "F.Fab")
		)
		(fp_line
			(start -0.12065 0.2794)
			(end -0.12065 0.3048)
			(stroke
				(width 0.1)
				(type default)
			)
			(layer "F.Fab")
		)
		(fp_line
			(start -0.12065 0.3048)
			(end -0.67945 0.3048)
			(stroke
				(width 0.1)
				(type default)
			)
			(layer "F.Fab")
		)
		(fp_line
			(start 0.120396 0.2794)
			(end -0.12065 0.2794)
			(stroke
				(width 0.1)
				(type default)
			)
			(layer "F.Fab")
		)
		(fp_line
			(start 0.120396 0.3048)
			(end 0.120396 0.2794)
			(stroke
				(width 0.1)
				(type default)
			)
			(layer "F.Fab")
		)
		(fp_line
			(start 0.12065 -0.3048)
			(end 0.67945 -0.3048)
			(stroke
				(width 0.1)
				(type default)
			)
			(layer "F.Fab")
		)
		(fp_line
			(start 0.12065 -0.2794)
			(end 0.12065 -0.3048)
			(stroke
				(width 0.1)
				(type default)
			)
			(layer "F.Fab")
		)
		(fp_line
			(start 0.67945 -0.3048)
			(end 0.67945 0.3048)
			(stroke
				(width 0.1)
				(type default)
			)
			(layer "F.Fab")
		)
		(fp_line
			(start 0.67945 0.3048)
			(end 0.120396 0.3048)
			(stroke
				(width 0.1)
				(type default)
			)
			(layer "F.Fab")
		)
		(pad "1" smd circle
			(at -0.40005 0)
			(size 0 0)
			(layers "F.Cu" "F.Mask" "F.Paste")
			(net "SMB_LM75_3_3V3AUX_SCL")
		)
		(pad "2" smd circle
			(at 0.40005 0)
			(size 0 0)
			(layers "F.Cu" "F.Mask" "F.Paste")
			(net "SMB_LM75_3_3V3AUX_SCL_R1")
		)
	)
)
